(kicad_pcb
	(version 20260206)
	(generator "pcbnew")
	(generator_version "10.0")
	(general
		(thickness 1.6)
		(legacy_teardrops no)
	)
	(paper "A4")
	(title_block
		(title "03242023_DA0F0TMBIJ0_F0T_Motherboard_J_brd_V01_OCP.brd")
		(comment 1 "Grand Teton / footprints 3535-3540 of 6105")
	)
	(layers
		(0 "F.Cu" signal "TOP")
		(4 "In1.Cu" signal "GND")
		(6 "In2.Cu" signal "IN1")
		(8 "In3.Cu" signal "GND1")
		(10 "In4.Cu" signal "IN2")
		(12 "In5.Cu" signal "GND2")
		(14 "In6.Cu" signal "IN3")
		(16 "In7.Cu" signal "GND3")
		(18 "In8.Cu" signal "VCC")
		(20 "In9.Cu" signal "VCC1")
		(22 "In10.Cu" signal "GND4")
		(24 "In11.Cu" signal "IN4")
		(26 "In12.Cu" signal "GND5")
		(28 "In13.Cu" signal "IN5")
		(30 "In14.Cu" signal "GND6")
		(32 "In15.Cu" signal "IN6")
		(34 "In16.Cu" signal "GND7")
		(2 "B.Cu" signal "BOTTOM")
		(9 "F.Adhes" user "F.Adhesive")
		(11 "B.Adhes" user "B.Adhesive")
		(13 "F.Paste" user "Package Geometry/Pastemask Top")
		(15 "B.Paste" user "Package Geometry/Pastemask Bottom")
		(5 "F.SilkS" user "Ref Des/Silkscreen Top")
		(7 "B.SilkS" user "Ref Des/Silkscreen Bottom")
		(1 "F.Mask" user "Board Geometry/Soldermask Top")
		(3 "B.Mask" user "Board Geometry/Soldermask Bottom")
		(17 "Dwgs.User" user "User.Drawings")
		(19 "Cmts.User" user "User.Comments")
		(21 "Eco1.User" user "User.Eco1")
		(23 "Eco2.User" user "User.Eco2")
		(25 "Edge.Cuts" user "Board Geometry/Outline")
		(27 "Margin" user)
		(31 "F.CrtYd" user "Package Geometry/Place Bound Top")
		(29 "B.CrtYd" user "Package Geometry/Place Bound Bottom")
		(35 "F.Fab" user "Ref Des/Assembly Top")
		(33 "B.Fab" user "Ref Des/Assembly Bottom")
	)
	(footprint ""
		(layer "F.Cu")
		(at 118.49608 -119.846598 90)
		(property "Reference" "R4053"
			(at 0 0 90)
			(layer "F.SilkS")
			(hide yes)
			(effects
				(font
					(size 1.27 1.27)
				)
			)
		)
		(property "Value" ""
			(at 0 0 90)
			(layer "F.Fab")
			(effects
				(font
					(size 1.27 1.27)
				)
			)
		)
		(duplicate_pad_numbers_are_jumpers no)
		(fp_line
			(start 0.7874 -0.4064)
			(end 0.7874 0.4064)
			(stroke
				(width 0.1524)
				(type default)
			)
			(layer "F.SilkS")
		)
		(fp_line
			(start -0.7874 -0.4064)
			(end 0.7874 -0.4064)
			(stroke
				(width 0.1524)
				(type default)
			)
			(layer "F.SilkS")
		)
		(fp_line
			(start 0.7874 0.4064)
			(end -0.7874 0.4064)
			(stroke
				(width 0.1524)
				(type default)
			)
			(layer "F.SilkS")
		)
		(fp_line
			(start -0.7874 0.4064)
			(end -0.7874 -0.4064)
			(stroke
				(width 0.1524)
				(type default)
			)
			(layer "F.SilkS")
		)
		(fp_line
			(start -0.12065 -0.305054)
			(end -0.12065 -0.2794)
			(stroke
				(width 0.1)
				(type default)
			)
			(layer "F.Fab")
		)
		(fp_line
			(start -0.67945 -0.305054)
			(end -0.12065 -0.305054)
			(stroke
				(width 0.1)
				(type default)
			)
			(layer "F.Fab")
		)
		(fp_line
			(start 0.67945 -0.3048)
			(end 0.67945 0.3048)
			(stroke
				(width 0.1)
				(type default)
			)
			(layer "F.Fab")
		)
		(fp_line
			(start 0.12065 -0.3048)
			(end 0.67945 -0.3048)
			(stroke
				(width 0.1)
				(type default)
			)
			(layer "F.Fab")
		)
		(fp_line
			(start 0.12065 -0.2794)
			(end 0.12065 -0.3048)
			(stroke
				(width 0.1)
				(type default)
			)
			(layer "F.Fab")
		)
		(fp_line
			(start -0.12065 -0.2794)
			(end 0.12065 -0.2794)
			(stroke
				(width 0.1)
				(type default)
			)
			(layer "F.Fab")
		)
		(fp_line
			(start 0.120396 0.2794)
			(end -0.12065 0.2794)
			(stroke
				(width 0.1)
				(type default)
			)
			(layer "F.Fab")
		)
		(fp_line
			(start -0.12065 0.2794)
			(end -0.12065 0.3048)
			(stroke
				(width 0.1)
				(type default)
			)
			(layer "F.Fab")
		)
		(fp_line
			(start 0.67945 0.3048)
			(end 0.120396 0.3048)
			(stroke
				(width 0.1)
				(type default)
			)
			(layer "F.Fab")
		)
		(fp_line
			(start 0.120396 0.3048)
			(end 0.120396 0.2794)
			(stroke
				(width 0.1)
				(type default)
			)
			(layer "F.Fab")
		)
		(fp_line
			(start -0.12065 0.3048)
			(end -0.67945 0.3048)
			(stroke
				(width 0.1)
				(type default)
			)
			(layer "F.Fab")
		)
		(fp_line
			(start -0.67945 0.3048)
			(end -0.67945 -0.305054)
			(stroke
				(width 0.1)
				(type default)
			)
			(layer "F.Fab")
		)
		(pad "1" smd circle
			(at -0.40005 0 90)
			(size 0 0)
			(layers "F.Cu" "F.Mask" "F.Paste")
			(net "PD_GTL2014_BMC_JTAG_DIR_0")
		)
		(pad "2" smd circle
			(at 0.40005 0 90)
			(size 0 0)
			(layers "F.Cu" "F.Mask" "F.Paste")
			(net "GND")
		)
	)
	(footprint ""
		(layer "F.Cu")
		(at 169.57294 -28.425648 -90)
		(property "Reference" "R4176"
			(at 0 0 270)
			(layer "F.SilkS")
			(hide yes)
			(effects
				(font
					(size 1.27 1.27)
				)
			)
		)
		(property "Value" ""
			(at 0 0 270)
			(layer "F.Fab")
			(effects
				(font
					(size 1.27 1.27)
				)
			)
		)
		(duplicate_pad_numbers_are_jumpers no)
		(fp_line
			(start -0.7874 0.4064)
			(end -0.7874 -0.4064)
			(stroke
				(width 0.1524)
				(type default)
			)
			(layer "F.SilkS")
		)
		(fp_line
			(start 0.7874 0.4064)
			(end -0.7874 0.4064)
			(stroke
				(width 0.1524)
				(type default)
			)
			(layer "F.SilkS")
		)
		(fp_line
			(start -0.7874 -0.4064)
			(end 0.7874 -0.4064)
			(stroke
				(width 0.1524)
				(type default)
			)
			(layer "F.SilkS")
		)
		(fp_line
			(start 0.7874 -0.4064)
			(end 0.7874 0.4064)
			(stroke
				(width 0.1524)
				(type default)
			)
			(layer "F.SilkS")
		)
		(fp_line
			(start -0.67945 0.3048)
			(end -0.67945 -0.305054)
			(stroke
				(width 0.1)
				(type default)
			)
			(layer "F.Fab")
		)
		(fp_line
			(start -0.12065 0.3048)
			(end -0.67945 0.3048)
			(stroke
				(width 0.1)
				(type default)
			)
			(layer "F.Fab")
		)
		(fp_line
			(start 0.120396 0.3048)
			(end 0.120396 0.2794)
			(stroke
				(width 0.1)
				(type default)
			)
			(layer "F.Fab")
		)
		(fp_line
			(start 0.67945 0.3048)
			(end 0.120396 0.3048)
			(stroke
				(width 0.1)
				(type default)
			)
			(layer "F.Fab")
		)
		(fp_line
			(start -0.12065 0.2794)
			(end -0.12065 0.3048)
			(stroke
				(width 0.1)
				(type default)
			)
			(layer "F.Fab")
		)
		(fp_line
			(start 0.120396 0.2794)
			(end -0.12065 0.2794)
			(stroke
				(width 0.1)
				(type default)
			)
			(layer "F.Fab")
		)
		(fp_line
			(start -0.12065 -0.2794)
			(end 0.12065 -0.2794)
			(stroke
				(width 0.1)
				(type default)
			)
			(layer "F.Fab")
		)
		(fp_line
			(start 0.12065 -0.2794)
			(end 0.12065 -0.3048)
			(stroke
				(width 0.1)
				(type default)
			)
			(layer "F.Fab")
		)
		(fp_line
			(start 0.12065 -0.3048)
			(end 0.67945 -0.3048)
			(stroke
				(width 0.1)
				(type default)
			)
			(layer "F.Fab")
		)
		(fp_line
			(start 0.67945 -0.3048)
			(end 0.67945 0.3048)
			(stroke
				(width 0.1)
				(type default)
			)
			(layer "F.Fab")
		)
		(fp_line
			(start -0.67945 -0.305054)
			(end -0.12065 -0.305054)
			(stroke
				(width 0.1)
				(type default)
			)
			(layer "F.Fab")
		)
		(fp_line
			(start -0.12065 -0.305054)
			(end -0.12065 -0.2794)
			(stroke
				(width 0.1)
				(type default)
			)
			(layer "F.Fab")
		)
		(pad "1" smd circle
			(at -0.40005 0 270)
			(size 0 0)
			(layers "F.Cu" "F.Mask" "F.Paste")
			(net "P3V3_AUX")
		)
		(pad "2" smd circle
			(at 0.40005 0 270)
			(size 0 0)
			(layers "F.Cu" "F.Mask" "F.Paste")
			(net "FM_LPC_ESPI_SEL")
		)
	)
	(footprint ""
		(layer "F.Cu")
		(at 27.595322 -133.430518 -90)
		(property "Reference" "PR274"
			(at 0 0 270)
			(layer "F.SilkS")
			(hide yes)
			(effects
				(font
					(size 1.27 1.27)
				)
			)
		)
		(property "Value" ""
			(at 0 0 270)
			(layer "F.Fab")
			(effects
				(font
					(size 1.27 1.27)
				)
			)
		)
		(duplicate_pad_numbers_are_jumpers no)
		(fp_line
			(start -0.7874 0.4064)
			(end -0.7874 -0.4064)
			(stroke
				(width 0.1524)
				(type default)
			)
			(layer "F.SilkS")
		)
		(fp_line
			(start 0.7874 0.4064)
			(end -0.7874 0.4064)
			(stroke
				(width 0.1524)
				(type default)
			)
			(layer "F.SilkS")
		)
		(fp_line
			(start -0.7874 -0.4064)
			(end 0.7874 -0.4064)
			(stroke
				(width 0.1524)
				(type default)
			)
			(layer "F.SilkS")
		)
		(fp_line
			(start 0.7874 -0.4064)
			(end 0.7874 0.4064)
			(stroke
				(width 0.1524)
				(type default)
			)
			(layer "F.SilkS")
		)
		(fp_line
			(start -0.67945 0.3048)
			(end -0.67945 -0.305054)
			(stroke
				(width 0.1)
				(type default)
			)
			(layer "F.Fab")
		)
		(fp_line
			(start -0.12065 0.3048)
			(end -0.67945 0.3048)
			(stroke
				(width 0.1)
				(type default)
			)
			(layer "F.Fab")
		)
		(fp_line
			(start 0.120396 0.3048)
			(end 0.120396 0.2794)
			(stroke
				(width 0.1)
				(type default)
			)
			(layer "F.Fab")
		)
		(fp_line
			(start 0.67945 0.3048)
			(end 0.120396 0.3048)
			(stroke
				(width 0.1)
				(type default)
			)
			(layer "F.Fab")
		)
		(fp_line
			(start -0.12065 0.2794)
			(end -0.12065 0.3048)
			(stroke
				(width 0.1)
				(type default)
			)
			(layer "F.Fab")
		)
		(fp_line
			(start 0.120396 0.2794)
			(end -0.12065 0.2794)
			(stroke
				(width 0.1)
				(type default)
			)
			(layer "F.Fab")
		)
		(fp_line
			(start -0.12065 -0.2794)
			(end 0.12065 -0.2794)
			(stroke
				(width 0.1)
				(type default)
			)
			(layer "F.Fab")
		)
		(fp_line
			(start 0.12065 -0.2794)
			(end 0.12065 -0.3048)
			(stroke
				(width 0.1)
				(type default)
			)
			(layer "F.Fab")
		)
		(fp_line
			(start 0.12065 -0.3048)
			(end 0.67945 -0.3048)
			(stroke
				(width 0.1)
				(type default)
			)
			(layer "F.Fab")
		)
		(fp_line
			(start 0.67945 -0.3048)
			(end 0.67945 0.3048)
			(stroke
				(width 0.1)
				(type default)
			)
			(layer "F.Fab")
		)
		(fp_line
			(start -0.67945 -0.305054)
			(end -0.12065 -0.305054)
			(stroke
				(width 0.1)
				(type default)
			)
			(layer "F.Fab")
		)
		(fp_line
			(start -0.12065 -0.305054)
			(end -0.12065 -0.2794)
			(stroke
				(width 0.1)
				(type default)
			)
			(layer "F.Fab")
		)
		(pad "1" smd circle
			(at -0.40005 0 270)
			(size 0 0)
			(layers "F.Cu" "F.Mask" "F.Paste")
			(net "SH_PVCCFA_EHV_CPU1")
		)
		(pad "2" smd circle
			(at 0.40005 0 270)
			(size 0 0)
			(layers "F.Cu" "F.Mask" "F.Paste")
			(net "SH_PVCCFA_EHV_CPU1_R")
		)
	)
	(footprint ""
		(layer "F.Cu")
		(at 202.322684 -105.315004 90)
		(property "Reference" "R4713"
			(at 0 0 90)
			(layer "F.SilkS")
			(hide yes)
			(effects
				(font
					(size 1.27 1.27)
				)
			)
		)
		(property "Value" ""
			(at 0 0 90)
			(layer "F.Fab")
			(effects
				(font
					(size 1.27 1.27)
				)
			)
		)
		(duplicate_pad_numbers_are_jumpers no)
		(fp_line
			(start 0.7874 -0.4064)
			(end 0.7874 0.4064)
			(stroke
				(width 0.1524)
				(type default)
			)
			(layer "F.SilkS")
		)
		(fp_line
			(start -0.7874 -0.4064)
			(end 0.7874 -0.4064)
			(stroke
				(width 0.1524)
				(type default)
			)
			(layer "F.SilkS")
		)
		(fp_line
			(start 0.7874 0.4064)
			(end -0.7874 0.4064)
			(stroke
				(width 0.1524)
				(type default)
			)
			(layer "F.SilkS")
		)
		(fp_line
			(start -0.7874 0.4064)
			(end -0.7874 -0.4064)
			(stroke
				(width 0.1524)
				(type default)
			)
			(layer "F.SilkS")
		)
		(fp_line
			(start -0.12065 -0.305054)
			(end -0.12065 -0.2794)
			(stroke
				(width 0.1)
				(type default)
			)
			(layer "F.Fab")
		)
		(fp_line
			(start -0.67945 -0.305054)
			(end -0.12065 -0.305054)
			(stroke
				(width 0.1)
				(type default)
			)
			(layer "F.Fab")
		)
		(fp_line
			(start 0.67945 -0.3048)
			(end 0.67945 0.3048)
			(stroke
				(width 0.1)
				(type default)
			)
			(layer "F.Fab")
		)
		(fp_line
			(start 0.12065 -0.3048)
			(end 0.67945 -0.3048)
			(stroke
				(width 0.1)
				(type default)
			)
			(layer "F.Fab")
		)
		(fp_line
			(start 0.12065 -0.2794)
			(end 0.12065 -0.3048)
			(stroke
				(width 0.1)
				(type default)
			)
			(layer "F.Fab")
		)
		(fp_line
			(start -0.12065 -0.2794)
			(end 0.12065 -0.2794)
			(stroke
				(width 0.1)
				(type default)
			)
			(layer "F.Fab")
		)
		(fp_line
			(start 0.120396 0.2794)
			(end -0.12065 0.2794)
			(stroke
				(width 0.1)
				(type default)
			)
			(layer "F.Fab")
		)
		(fp_line
			(start -0.12065 0.2794)
			(end -0.12065 0.3048)
			(stroke
				(width 0.1)
				(type default)
			)
			(layer "F.Fab")
		)
		(fp_line
			(start 0.67945 0.3048)
			(end 0.120396 0.3048)
			(stroke
				(width 0.1)
				(type default)
			)
			(layer "F.Fab")
		)
		(fp_line
			(start 0.120396 0.3048)
			(end 0.120396 0.2794)
			(stroke
				(width 0.1)
				(type default)
			)
			(layer "F.Fab")
		)
		(fp_line
			(start -0.12065 0.3048)
			(end -0.67945 0.3048)
			(stroke
				(width 0.1)
				(type default)
			)
			(layer "F.Fab")
		)
		(fp_line
			(start -0.67945 0.3048)
			(end -0.67945 -0.305054)
			(stroke
				(width 0.1)
				(type default)
			)
			(layer "F.Fab")
		)
		(pad "1" smd circle
			(at -0.40005 0 90)
			(size 0 0)
			(layers "F.Cu" "F.Mask" "F.Paste")
			(net "RST_PFR_OVR_SRTC")
		)
		(pad "2" smd circle
			(at 0.40005 0 90)
			(size 0 0)
			(layers "F.Cu" "F.Mask" "F.Paste")
			(net "GND")
		)
	)
	(footprint ""
		(layer "F.Cu")
		(at 453.345804 -71.245984 -90)
		(property "Reference" "PC570"
			(at 0 0 270)
			(layer "F.SilkS")
			(hide yes)
			(effects
				(font
					(size 1.27 1.27)
				)
			)
		)
		(property "Value" ""
			(at 0 0 270)
			(layer "F.Fab")
			(effects
				(font
					(size 1.27 1.27)
				)
			)
		)
		(duplicate_pad_numbers_are_jumpers no)
		(fp_line
			(start -1.524 0.762)
			(end -1.524 -0.762)
			(stroke
				(width 0.1524)
				(type default)
			)
			(layer "F.SilkS")
		)
		(fp_line
			(start 1.524 0.762)
			(end -1.524 0.762)
			(stroke
				(width 0.1524)
				(type default)
			)
			(layer "F.SilkS")
		)
		(fp_line
			(start -1.524 -0.762)
			(end 1.524 -0.762)
			(stroke
				(width 0.1524)
				(type default)
			)
			(layer "F.SilkS")
		)
		(fp_line
			(start 1.524 -0.762)
			(end 1.524 0.762)
			(stroke
				(width 0.1524)
				(type default)
			)
			(layer "F.SilkS")
		)
		(fp_line
			(start -1.1049 0.724916)
			(end 1.1049 0.724916)
			(stroke
				(width 0.1)
				(type default)
			)
			(layer "F.Fab")
		)
		(fp_line
			(start 1.1049 0.724916)
			(end 1.1049 -0.724916)
			(stroke
				(width 0.1)
				(type default)
			)
			(layer "F.Fab")
		)
		(fp_line
			(start -1.1049 -0.724916)
			(end -1.1049 0.724916)
			(stroke
				(width 0.1)
				(type default)
			)
			(layer "F.Fab")
		)
		(fp_line
			(start 1.1049 -0.724916)
			(end -1.1049 -0.724916)
			(stroke
				(width 0.1)
				(type default)
			)
			(layer "F.Fab")
		)
		(pad "1" smd rect
			(at -0.889 0 90)
			(size 1.016 1.27)
			(layers "F.Cu" "F.Mask" "F.Paste")
			(net "SW_P3V3_AUX_FLT")
		)
		(pad "2" smd rect
			(at 0.889 0 90)
			(size 1.016 1.27)
			(layers "F.Cu" "F.Mask" "F.Paste")
			(net "GND")
		)
	)
	(footprint ""
		(layer "F.Cu")
		(at 180.79212 -411.20822 90)
		(property "Reference" "R4792"
			(at 0 0 90)
			(layer "F.SilkS")
			(hide yes)
			(effects
				(font
					(size 1.27 1.27)
				)
			)
		)
		(property "Value" ""
			(at 0 0 90)
			(layer "F.Fab")
			(effects
				(font
					(size 1.27 1.27)
				)
			)
		)
		(duplicate_pad_numbers_are_jumpers no)
		(fp_line
			(start 0.7874 -0.4064)
			(end 0.7874 0.4064)
			(stroke
				(width 0.1524)
				(type default)
			)
			(layer "F.SilkS")
		)
		(fp_line
			(start -0.7874 -0.4064)
			(end 0.7874 -0.4064)
			(stroke
				(width 0.1524)
				(type default)
			)
			(layer "F.SilkS")
		)
		(fp_line
			(start 0.7874 0.4064)
			(end -0.7874 0.4064)
			(stroke
				(width 0.1524)
				(type default)
			)
			(layer "F.SilkS")
		)
		(fp_line
			(start -0.7874 0.4064)
			(end -0.7874 -0.4064)
			(stroke
				(width 0.1524)
				(type default)
			)
			(layer "F.SilkS")
		)
		(fp_line
			(start -0.12065 -0.305054)
			(end -0.12065 -0.2794)
			(stroke
				(width 0.1)
				(type default)
			)
			(layer "F.Fab")
		)
		(fp_line
			(start -0.67945 -0.305054)
			(end -0.12065 -0.305054)
			(stroke
				(width 0.1)
				(type default)
			)
			(layer "F.Fab")
		)
		(fp_line
			(start 0.67945 -0.3048)
			(end 0.67945 0.3048)
			(stroke
				(width 0.1)
				(type default)
			)
			(layer "F.Fab")
		)
		(fp_line
			(start 0.12065 -0.3048)
			(end 0.67945 -0.3048)
			(stroke
				(width 0.1)
				(type default)
			)
			(layer "F.Fab")
		)
		(fp_line
			(start 0.12065 -0.2794)
			(end 0.12065 -0.3048)
			(stroke
				(width 0.1)
				(type default)
			)
			(layer "F.Fab")
		)
		(fp_line
			(start -0.12065 -0.2794)
			(end 0.12065 -0.2794)
			(stroke
				(width 0.1)
				(type default)
			)
			(layer "F.Fab")
		)
		(fp_line
			(start 0.120396 0.2794)
			(end -0.12065 0.2794)
			(stroke
				(width 0.1)
				(type default)
			)
			(layer "F.Fab")
		)
		(fp_line
			(start -0.12065 0.2794)
			(end -0.12065 0.3048)
			(stroke
				(width 0.1)
				(type default)
			)
			(layer "F.Fab")
		)
		(fp_line
			(start 0.67945 0.3048)
			(end 0.120396 0.3048)
			(stroke
				(width 0.1)
				(type default)
			)
			(layer "F.Fab")
		)
		(fp_line
			(start 0.120396 0.3048)
			(end 0.120396 0.2794)
			(stroke
				(width 0.1)
				(type default)
			)
			(layer "F.Fab")
		)
		(fp_line
			(start -0.12065 0.3048)
			(end -0.67945 0.3048)
			(stroke
				(width 0.1)
				(type default)
			)
			(layer "F.Fab")
		)
		(fp_line
			(start -0.67945 0.3048)
			(end -0.67945 -0.305054)
			(stroke
				(width 0.1)
				(type default)
			)
			(layer "F.Fab")
		)
		(pad "1" smd circle
			(at -0.40005 0 90)
			(size 0 0)
			(layers "F.Cu" "F.Mask" "F.Paste")
			(net "P3V3_AUX")
		)
		(pad "2" smd circle
			(at 0.40005 0 90)
			(size 0 0)
			(layers "F.Cu" "F.Mask" "F.Paste")
			(net "OC_P2V5_COMP")
		)
	)
)
